(kicad_pcb
	(version 20260206)
	(generator "pcbnew")
	(generator_version "10.0")
	(general
		(thickness 1.6)
		(legacy_teardrops no)
	)
	(paper "A4")
	(title_block
		(title "01162023_DA0F0TEBIF0_F0T_Expander_BD_F_brd_V02_OCP.brd")
		(comment 1 "Grand Teton / footprints 7999-8007 of 9728")
	)
	(layers
		(0 "F.Cu" signal "TOP")
		(4 "In1.Cu" signal "GND")
		(6 "In2.Cu" signal "VCC")
		(8 "In3.Cu" signal "VCC1")
		(10 "In4.Cu" signal "GND1")
		(12 "In5.Cu" signal "IN1")
		(14 "In6.Cu" signal "GND2")
		(16 "In7.Cu" signal "IN2")
		(18 "In8.Cu" signal "GND3")
		(20 "In9.Cu" signal "IN3")
		(22 "In10.Cu" signal "GND4")
		(24 "In11.Cu" signal "IN4")
		(26 "In12.Cu" signal "GND5")
		(28 "In13.Cu" signal "IN5")
		(30 "In14.Cu" signal "GND6")
		(32 "In15.Cu" signal "IN6")
		(34 "In16.Cu" signal "GND7")
		(2 "B.Cu" signal "BOTTOM")
		(9 "F.Adhes" user "F.Adhesive")
		(11 "B.Adhes" user "B.Adhesive")
		(13 "F.Paste" user "Package Geometry/Pastemask Top")
		(15 "B.Paste" user "Package Geometry/Pastemask Bottom")
		(5 "F.SilkS" user "Ref Des/Silkscreen Top")
		(7 "B.SilkS" user "Ref Des/Silkscreen Bottom")
		(1 "F.Mask" user "Board Geometry/Soldermask Top")
		(3 "B.Mask" user "Board Geometry/Soldermask Bottom")
		(17 "Dwgs.User" user "User.Drawings")
		(19 "Cmts.User" user "User.Comments")
		(21 "Eco1.User" user "User.Eco1")
		(23 "Eco2.User" user "User.Eco2")
		(25 "Edge.Cuts" user "Board Geometry/Outline")
		(27 "Margin" user)
		(31 "F.CrtYd" user "Package Geometry/Place Bound Top")
		(29 "B.CrtYd" user "Package Geometry/Place Bound Bottom")
		(35 "F.Fab" user "Ref Des/Assembly Top")
		(33 "B.Fab" user "Ref Des/Assembly Bottom")
	)
	(footprint ""
		(layer "B.Cu")
		(at 310.70169 -295.422066 180)
		(property "Reference" "C3253"
			(at 0 0 0)
			(layer "B.SilkS")
			(hide yes)
			(effects
				(font
					(size 1.27 1.27)
				)
				(justify mirror)
			)
		)
		(property "Value" ""
			(at 0 0 0)
			(layer "B.Fab")
			(effects
				(font
					(size 1.27 1.27)
				)
				(justify mirror)
			)
		)
		(duplicate_pad_numbers_are_jumpers no)
		(fp_line
			(start 1.2954 0.5842)
			(end 1.2954 -0.5842)
			(stroke
				(width 0.1524)
				(type default)
			)
			(layer "B.SilkS")
		)
		(fp_line
			(start 1.2954 -0.5842)
			(end -1.2954 -0.5842)
			(stroke
				(width 0.1524)
				(type default)
			)
			(layer "B.SilkS")
		)
		(fp_line
			(start -1.2954 0.5842)
			(end 1.2954 0.5842)
			(stroke
				(width 0.1524)
				(type default)
			)
			(layer "B.SilkS")
		)
		(fp_line
			(start -1.2954 -0.5842)
			(end -1.2954 0.5842)
			(stroke
				(width 0.1524)
				(type default)
			)
			(layer "B.SilkS")
		)
		(fp_line
			(start 1.1938 0.4064)
			(end 1.1938 -0.4064)
			(stroke
				(width 0.1)
				(type default)
			)
			(layer "B.Fab")
		)
		(fp_line
			(start 1.1938 -0.4064)
			(end 0.8636 -0.4064)
			(stroke
				(width 0.1)
				(type default)
			)
			(layer "B.Fab")
		)
		(fp_line
			(start 0.8636 0.4572)
			(end 0.8636 0.4064)
			(stroke
				(width 0.1)
				(type default)
			)
			(layer "B.Fab")
		)
		(fp_line
			(start 0.8636 0.4064)
			(end 1.1938 0.4064)
			(stroke
				(width 0.1)
				(type default)
			)
			(layer "B.Fab")
		)
		(fp_line
			(start 0.8636 -0.4064)
			(end 0.8636 -0.4572)
			(stroke
				(width 0.1)
				(type default)
			)
			(layer "B.Fab")
		)
		(fp_line
			(start 0.8636 -0.4572)
			(end -0.8636 -0.4572)
			(stroke
				(width 0.1)
				(type default)
			)
			(layer "B.Fab")
		)
		(fp_line
			(start -0.8636 0.4572)
			(end 0.8636 0.4572)
			(stroke
				(width 0.1)
				(type default)
			)
			(layer "B.Fab")
		)
		(fp_line
			(start -0.8636 0.4064)
			(end -0.8636 0.4572)
			(stroke
				(width 0.1)
				(type default)
			)
			(layer "B.Fab")
		)
		(fp_line
			(start -0.8636 -0.4064)
			(end -1.1938 -0.4064)
			(stroke
				(width 0.1)
				(type default)
			)
			(layer "B.Fab")
		)
		(fp_line
			(start -0.8636 -0.4572)
			(end -0.8636 -0.4064)
			(stroke
				(width 0.1)
				(type default)
			)
			(layer "B.Fab")
		)
		(fp_line
			(start -1.1938 0.4064)
			(end -0.8636 0.4064)
			(stroke
				(width 0.1)
				(type default)
			)
			(layer "B.Fab")
		)
		(fp_line
			(start -1.1938 -0.4064)
			(end -1.1938 0.4064)
			(stroke
				(width 0.1)
				(type default)
			)
			(layer "B.Fab")
		)
		(pad "1" smd rect
			(at 0.7366 0 90)
			(size 0.7112 0.8128)
			(layers "B.Cu" "B.Mask" "B.Paste")
			(net "P1V25_PEX2")
		)
		(pad "2" smd rect
			(at -0.7366 0 90)
			(size 0.7112 0.8128)
			(layers "B.Cu" "B.Mask" "B.Paste")
			(net "GND")
		)
	)
	(footprint ""
		(layer "B.Cu")
		(at 166.725092 -286.399732 90)
		(property "Reference" "C3120"
			(at 0 0 90)
			(layer "B.SilkS")
			(hide yes)
			(effects
				(font
					(size 1.27 1.27)
				)
				(justify mirror)
			)
		)
		(property "Value" ""
			(at 0 0 90)
			(layer "B.Fab")
			(effects
				(font
					(size 1.27 1.27)
				)
				(justify mirror)
			)
		)
		(duplicate_pad_numbers_are_jumpers no)
		(fp_line
			(start 0.299974 -0.150114)
			(end -0.299974 -0.150114)
			(stroke
				(width 0.1)
				(type default)
			)
			(layer "B.Fab")
		)
		(fp_line
			(start -0.299974 -0.150114)
			(end -0.299974 0.150114)
			(stroke
				(width 0.1)
				(type default)
			)
			(layer "B.Fab")
		)
		(fp_line
			(start 0.299974 0.150114)
			(end 0.299974 -0.150114)
			(stroke
				(width 0.1)
				(type default)
			)
			(layer "B.Fab")
		)
		(fp_line
			(start -0.299974 0.150114)
			(end 0.299974 0.150114)
			(stroke
				(width 0.1)
				(type default)
			)
			(layer "B.Fab")
		)
		(pad "1" smd rect
			(at 0.2667 0 270)
			(size 0.3048 0.381)
			(layers "B.Cu" "B.Mask" "B.Paste")
			(net "P1V25_SERDES_VDDPLL_PEX1")
		)
		(pad "2" smd rect
			(at -0.2667 0 270)
			(size 0.3048 0.381)
			(layers "B.Cu" "B.Mask" "B.Paste")
			(net "GND")
		)
	)
	(footprint ""
		(layer "B.Cu")
		(at 200.058274 -259.311648 -90)
		(property "Reference" "R6339"
			(at 0 0 90)
			(layer "B.SilkS")
			(hide yes)
			(effects
				(font
					(size 1.27 1.27)
				)
				(justify mirror)
			)
		)
		(property "Value" ""
			(at 0 0 90)
			(layer "B.Fab")
			(effects
				(font
					(size 1.27 1.27)
				)
				(justify mirror)
			)
		)
		(duplicate_pad_numbers_are_jumpers no)
		(fp_line
			(start -0.7874 0.4064)
			(end 0.7874 0.4064)
			(stroke
				(width 0.1524)
				(type default)
			)
			(layer "B.SilkS")
		)
		(fp_line
			(start 0.7874 0.4064)
			(end 0.7874 -0.4064)
			(stroke
				(width 0.1524)
				(type default)
			)
			(layer "B.SilkS")
		)
		(fp_line
			(start -0.7874 -0.4064)
			(end -0.7874 0.4064)
			(stroke
				(width 0.1524)
				(type default)
			)
			(layer "B.SilkS")
		)
		(fp_line
			(start 0.7874 -0.4064)
			(end -0.7874 -0.4064)
			(stroke
				(width 0.1524)
				(type default)
			)
			(layer "B.SilkS")
		)
		(fp_line
			(start -0.67945 0.3048)
			(end -0.120396 0.3048)
			(stroke
				(width 0.1)
				(type default)
			)
			(layer "B.Fab")
		)
		(fp_line
			(start -0.120396 0.3048)
			(end -0.120396 0.2794)
			(stroke
				(width 0.1)
				(type default)
			)
			(layer "B.Fab")
		)
		(fp_line
			(start 0.12065 0.3048)
			(end 0.67945 0.3048)
			(stroke
				(width 0.1)
				(type default)
			)
			(layer "B.Fab")
		)
		(fp_line
			(start 0.67945 0.3048)
			(end 0.67945 -0.305054)
			(stroke
				(width 0.1)
				(type default)
			)
			(layer "B.Fab")
		)
		(fp_line
			(start -0.120396 0.2794)
			(end 0.12065 0.2794)
			(stroke
				(width 0.1)
				(type default)
			)
			(layer "B.Fab")
		)
		(fp_line
			(start 0.12065 0.2794)
			(end 0.12065 0.3048)
			(stroke
				(width 0.1)
				(type default)
			)
			(layer "B.Fab")
		)
		(fp_line
			(start -0.12065 -0.2794)
			(end -0.12065 -0.3048)
			(stroke
				(width 0.1)
				(type default)
			)
			(layer "B.Fab")
		)
		(fp_line
			(start 0.12065 -0.2794)
			(end -0.12065 -0.2794)
			(stroke
				(width 0.1)
				(type default)
			)
			(layer "B.Fab")
		)
		(fp_line
			(start -0.67945 -0.3048)
			(end -0.67945 0.3048)
			(stroke
				(width 0.1)
				(type default)
			)
			(layer "B.Fab")
		)
		(fp_line
			(start -0.12065 -0.3048)
			(end -0.67945 -0.3048)
			(stroke
				(width 0.1)
				(type default)
			)
			(layer "B.Fab")
		)
		(fp_line
			(start 0.12065 -0.305054)
			(end 0.12065 -0.2794)
			(stroke
				(width 0.1)
				(type default)
			)
			(layer "B.Fab")
		)
		(fp_line
			(start 0.67945 -0.305054)
			(end 0.12065 -0.305054)
			(stroke
				(width 0.1)
				(type default)
			)
			(layer "B.Fab")
		)
		(pad "1" smd circle
			(at 0.40005 0 90)
			(size 0 0)
			(layers "B.Cu" "B.Mask" "B.Paste")
			(net "PEX_MUX_A0")
		)
		(pad "2" smd circle
			(at -0.40005 0 90)
			(size 0 0)
			(layers "B.Cu" "B.Mask" "B.Paste")
			(net "GND")
		)
	)
	(footprint ""
		(layer "B.Cu")
		(at 451.298056 -266.996672)
		(property "Reference" "R6138"
			(at 0 0 0)
			(layer "B.SilkS")
			(hide yes)
			(effects
				(font
					(size 1.27 1.27)
				)
				(justify mirror)
			)
		)
		(property "Value" ""
			(at 0 0 0)
			(layer "B.Fab")
			(effects
				(font
					(size 1.27 1.27)
				)
				(justify mirror)
			)
		)
		(duplicate_pad_numbers_are_jumpers no)
		(fp_line
			(start -2.576322 -1.1303)
			(end -2.576322 1.1303)
			(stroke
				(width 0.1524)
				(type default)
			)
			(layer "B.SilkS")
		)
		(fp_line
			(start -2.576322 1.1303)
			(end 2.576322 1.1303)
			(stroke
				(width 0.1524)
				(type default)
			)
			(layer "B.SilkS")
		)
		(fp_line
			(start 2.576322 -1.1303)
			(end -2.576322 -1.1303)
			(stroke
				(width 0.1524)
				(type default)
			)
			(layer "B.SilkS")
		)
		(fp_line
			(start 2.576322 1.1303)
			(end 2.576322 -1.1303)
			(stroke
				(width 0.1524)
				(type default)
			)
			(layer "B.SilkS")
		)
		(fp_line
			(start -1.649984 -0.899922)
			(end 1.649984 -0.899922)
			(stroke
				(width 0.1)
				(type default)
			)
			(layer "B.Fab")
		)
		(fp_line
			(start -1.649984 0.899922)
			(end -1.649984 -0.899922)
			(stroke
				(width 0.1)
				(type default)
			)
			(layer "B.Fab")
		)
		(fp_line
			(start 1.649984 -0.899922)
			(end 1.649984 0.899922)
			(stroke
				(width 0.1)
				(type default)
			)
			(layer "B.Fab")
		)
		(fp_line
			(start 1.649984 0.899922)
			(end -1.649984 0.899922)
			(stroke
				(width 0.1)
				(type default)
			)
			(layer "B.Fab")
		)
		(pad "1A" smd rect
			(at 1.700022 0 180)
			(size 1.4986 2.0066)
			(layers "B.Cu" "B.Mask" "B.Paste")
			(net "P1V25_PEX3")
		)
		(pad "1B" smd rect
			(at 1.077722 0 180)
			(size 0.254 0.508)
			(layers "B.Cu" "B.Mask" "B.Paste")
			(net "P1V25_PEX3")
		)
		(pad "2A" smd rect
			(at -1.700022 0 180)
			(size 1.4986 2.0066)
			(layers "B.Cu" "B.Mask" "B.Paste")
			(net "P1V25_SERDES_VDDPLL_PEX3")
		)
		(pad "2B" smd rect
			(at -1.077722 0 180)
			(size 0.254 0.508)
			(layers "B.Cu" "B.Mask" "B.Paste")
			(net "P1V25_SERDES_VDDPLL_PEX3")
		)
	)
	(footprint ""
		(layer "B.Cu")
		(at 15.365222 -383.98069 180)
		(property "Reference" "C4476"
			(at 0 0 0)
			(layer "B.SilkS")
			(hide yes)
			(effects
				(font
					(size 1.27 1.27)
				)
				(justify mirror)
			)
		)
		(property "Value" ""
			(at 0 0 0)
			(layer "B.Fab")
			(effects
				(font
					(size 1.27 1.27)
				)
				(justify mirror)
			)
		)
		(duplicate_pad_numbers_are_jumpers no)
		(fp_line
			(start 0.7874 0.4064)
			(end 0.7874 -0.4064)
			(stroke
				(width 0.1524)
				(type default)
			)
			(layer "B.SilkS")
		)
		(fp_line
			(start 0.7874 -0.4064)
			(end -0.7874 -0.4064)
			(stroke
				(width 0.1524)
				(type default)
			)
			(layer "B.SilkS")
		)
		(fp_line
			(start -0.7874 0.4064)
			(end 0.7874 0.4064)
			(stroke
				(width 0.1524)
				(type default)
			)
			(layer "B.SilkS")
		)
		(fp_line
			(start -0.7874 -0.4064)
			(end -0.7874 0.4064)
			(stroke
				(width 0.1524)
				(type default)
			)
			(layer "B.SilkS")
		)
		(fp_line
			(start 0.67945 0.3048)
			(end 0.67945 -0.305054)
			(stroke
				(width 0.1)
				(type default)
			)
			(layer "B.Fab")
		)
		(fp_line
			(start 0.67945 -0.305054)
			(end 0.12065 -0.305054)
			(stroke
				(width 0.1)
				(type default)
			)
			(layer "B.Fab")
		)
		(fp_line
			(start 0.12065 0.3048)
			(end 0.67945 0.3048)
			(stroke
				(width 0.1)
				(type default)
			)
			(layer "B.Fab")
		)
		(fp_line
			(start 0.12065 0.2794)
			(end 0.12065 0.3048)
			(stroke
				(width 0.1)
				(type default)
			)
			(layer "B.Fab")
		)
		(fp_line
			(start 0.12065 -0.2794)
			(end -0.12065 -0.2794)
			(stroke
				(width 0.1)
				(type default)
			)
			(layer "B.Fab")
		)
		(fp_line
			(start 0.12065 -0.305054)
			(end 0.12065 -0.2794)
			(stroke
				(width 0.1)
				(type default)
			)
			(layer "B.Fab")
		)
		(fp_line
			(start -0.120396 0.3048)
			(end -0.120396 0.2794)
			(stroke
				(width 0.1)
				(type default)
			)
			(layer "B.Fab")
		)
		(fp_line
			(start -0.120396 0.2794)
			(end 0.12065 0.2794)
			(stroke
				(width 0.1)
				(type default)
			)
			(layer "B.Fab")
		)
		(fp_line
			(start -0.12065 -0.2794)
			(end -0.12065 -0.3048)
			(stroke
				(width 0.1)
				(type default)
			)
			(layer "B.Fab")
		)
		(fp_line
			(start -0.12065 -0.3048)
			(end -0.67945 -0.3048)
			(stroke
				(width 0.1)
				(type default)
			)
			(layer "B.Fab")
		)
		(fp_line
			(start -0.67945 0.3048)
			(end -0.120396 0.3048)
			(stroke
				(width 0.1)
				(type default)
			)
			(layer "B.Fab")
		)
		(fp_line
			(start -0.67945 -0.3048)
			(end -0.67945 0.3048)
			(stroke
				(width 0.1)
				(type default)
			)
			(layer "B.Fab")
		)
		(pad "1" smd circle
			(at 0.40005 0)
			(size 0 0)
			(layers "B.Cu" "B.Mask" "B.Paste")
			(net "P1V2_USB_8042")
		)
		(pad "2" smd circle
			(at -0.40005 0)
			(size 0 0)
			(layers "B.Cu" "B.Mask" "B.Paste")
			(net "GND")
		)
	)
	(footprint ""
		(layer "B.Cu")
		(at 62.499748 -292.099746 90)
		(property "Reference" "C1230"
			(at 0 0 90)
			(layer "B.SilkS")
			(hide yes)
			(effects
				(font
					(size 1.27 1.27)
				)
				(justify mirror)
			)
		)
		(property "Value" ""
			(at 0 0 90)
			(layer "B.Fab")
			(effects
				(font
					(size 1.27 1.27)
				)
				(justify mirror)
			)
		)
		(duplicate_pad_numbers_are_jumpers no)
		(fp_line
			(start 0.299974 -0.150114)
			(end -0.299974 -0.150114)
			(stroke
				(width 0.1)
				(type default)
			)
			(layer "B.Fab")
		)
		(fp_line
			(start -0.299974 -0.150114)
			(end -0.299974 0.150114)
			(stroke
				(width 0.1)
				(type default)
			)
			(layer "B.Fab")
		)
		(fp_line
			(start 0.299974 0.150114)
			(end 0.299974 -0.150114)
			(stroke
				(width 0.1)
				(type default)
			)
			(layer "B.Fab")
		)
		(fp_line
			(start -0.299974 0.150114)
			(end 0.299974 0.150114)
			(stroke
				(width 0.1)
				(type default)
			)
			(layer "B.Fab")
		)
		(pad "1" smd rect
			(at 0.2667 0 270)
			(size 0.3048 0.381)
			(layers "B.Cu" "B.Mask" "B.Paste")
			(net "P0V8_SERDES_VDDA_PEX0")
		)
		(pad "2" smd rect
			(at -0.2667 0 270)
			(size 0.3048 0.381)
			(layers "B.Cu" "B.Mask" "B.Paste")
			(net "GND")
		)
	)
	(footprint ""
		(layer "B.Cu")
		(at 413.649922 -303.499774 -90)
		(property "Reference" "C3426"
			(at 0 0 90)
			(layer "B.SilkS")
			(hide yes)
			(effects
				(font
					(size 1.27 1.27)
				)
				(justify mirror)
			)
		)
		(property "Value" ""
			(at 0 0 90)
			(layer "B.Fab")
			(effects
				(font
					(size 1.27 1.27)
				)
				(justify mirror)
			)
		)
		(duplicate_pad_numbers_are_jumpers no)
		(fp_line
			(start -0.299974 0.150114)
			(end 0.299974 0.150114)
			(stroke
				(width 0.1)
				(type default)
			)
			(layer "B.Fab")
		)
		(fp_line
			(start 0.299974 0.150114)
			(end 0.299974 -0.150114)
			(stroke
				(width 0.1)
				(type default)
			)
			(layer "B.Fab")
		)
		(fp_line
			(start -0.299974 -0.150114)
			(end -0.299974 0.150114)
			(stroke
				(width 0.1)
				(type default)
			)
			(layer "B.Fab")
		)
		(fp_line
			(start 0.299974 -0.150114)
			(end -0.299974 -0.150114)
			(stroke
				(width 0.1)
				(type default)
			)
			(layer "B.Fab")
		)
		(pad "1" smd rect
			(at 0.2667 0 90)
			(size 0.3048 0.381)
			(layers "B.Cu" "B.Mask" "B.Paste")
			(net "P1V25_PEX3")
		)
		(pad "2" smd rect
			(at -0.2667 0 90)
			(size 0.3048 0.381)
			(layers "B.Cu" "B.Mask" "B.Paste")
			(net "GND")
		)
	)
	(footprint ""
		(layer "B.Cu")
		(at 102.782878 -337.481672 -90)
		(property "Reference" "C2696"
			(at 0 0 90)
			(layer "B.SilkS")
			(hide yes)
			(effects
				(font
					(size 1.27 1.27)
				)
				(justify mirror)
			)
		)
		(property "Value" ""
			(at 0 0 90)
			(layer "B.Fab")
			(effects
				(font
					(size 1.27 1.27)
				)
				(justify mirror)
			)
		)
		(duplicate_pad_numbers_are_jumpers no)
		(fp_line
			(start -0.7874 0.4064)
			(end 0.7874 0.4064)
			(stroke
				(width 0.1524)
				(type default)
			)
			(layer "B.SilkS")
		)
		(fp_line
			(start 0.7874 0.4064)
			(end 0.7874 -0.4064)
			(stroke
				(width 0.1524)
				(type default)
			)
			(layer "B.SilkS")
		)
		(fp_line
			(start -0.7874 -0.4064)
			(end -0.7874 0.4064)
			(stroke
				(width 0.1524)
				(type default)
			)
			(layer "B.SilkS")
		)
		(fp_line
			(start 0.7874 -0.4064)
			(end -0.7874 -0.4064)
			(stroke
				(width 0.1524)
				(type default)
			)
			(layer "B.SilkS")
		)
		(fp_line
			(start -0.67945 0.3048)
			(end -0.120396 0.3048)
			(stroke
				(width 0.1)
				(type default)
			)
			(layer "B.Fab")
		)
		(fp_line
			(start -0.120396 0.3048)
			(end -0.120396 0.2794)
			(stroke
				(width 0.1)
				(type default)
			)
			(layer "B.Fab")
		)
		(fp_line
			(start 0.12065 0.3048)
			(end 0.67945 0.3048)
			(stroke
				(width 0.1)
				(type default)
			)
			(layer "B.Fab")
		)
		(fp_line
			(start 0.67945 0.3048)
			(end 0.67945 -0.305054)
			(stroke
				(width 0.1)
				(type default)
			)
			(layer "B.Fab")
		)
		(fp_line
			(start -0.120396 0.2794)
			(end 0.12065 0.2794)
			(stroke
				(width 0.1)
				(type default)
			)
			(layer "B.Fab")
		)
		(fp_line
			(start 0.12065 0.2794)
			(end 0.12065 0.3048)
			(stroke
				(width 0.1)
				(type default)
			)
			(layer "B.Fab")
		)
		(fp_line
			(start -0.12065 -0.2794)
			(end -0.12065 -0.3048)
			(stroke
				(width 0.1)
				(type default)
			)
			(layer "B.Fab")
		)
		(fp_line
			(start 0.12065 -0.2794)
			(end -0.12065 -0.2794)
			(stroke
				(width 0.1)
				(type default)
			)
			(layer "B.Fab")
		)
		(fp_line
			(start -0.67945 -0.3048)
			(end -0.67945 0.3048)
			(stroke
				(width 0.1)
				(type default)
			)
			(layer "B.Fab")
		)
		(fp_line
			(start -0.12065 -0.3048)
			(end -0.67945 -0.3048)
			(stroke
				(width 0.1)
				(type default)
			)
			(layer "B.Fab")
		)
		(fp_line
			(start 0.12065 -0.305054)
			(end 0.12065 -0.2794)
			(stroke
				(width 0.1)
				(type default)
			)
			(layer "B.Fab")
		)
		(fp_line
			(start 0.67945 -0.305054)
			(end 0.12065 -0.305054)
			(stroke
				(width 0.1)
				(type default)
			)
			(layer "B.Fab")
		)
		(pad "1" smd circle
			(at 0.40005 0 90)
			(size 0 0)
			(layers "B.Cu" "B.Mask" "B.Paste")
			(net "P3V3_CLK_BUFFER_9ZXL0451E_VZX3P3")
		)
		(pad "2" smd circle
			(at -0.40005 0 90)
			(size 0 0)
			(layers "B.Cu" "B.Mask" "B.Paste")
			(net "GND")
		)
	)
	(footprint ""
		(layer "B.Cu")
		(at 408.899868 -303.499774 -90)
		(property "Reference" "C3434"
			(at 0 0 90)
			(layer "B.SilkS")
			(hide yes)
			(effects
				(font
					(size 1.27 1.27)
				)
				(justify mirror)
			)
		)
		(property "Value" ""
			(at 0 0 90)
			(layer "B.Fab")
			(effects
				(font
					(size 1.27 1.27)
				)
				(justify mirror)
			)
		)
		(duplicate_pad_numbers_are_jumpers no)
		(fp_line
			(start -0.299974 0.150114)
			(end 0.299974 0.150114)
			(stroke
				(width 0.1)
				(type default)
			)
			(layer "B.Fab")
		)
		(fp_line
			(start 0.299974 0.150114)
			(end 0.299974 -0.150114)
			(stroke
				(width 0.1)
				(type default)
			)
			(layer "B.Fab")
		)
		(fp_line
			(start -0.299974 -0.150114)
			(end -0.299974 0.150114)
			(stroke
				(width 0.1)
				(type default)
			)
			(layer "B.Fab")
		)
		(fp_line
			(start 0.299974 -0.150114)
			(end -0.299974 -0.150114)
			(stroke
				(width 0.1)
				(type default)
			)
			(layer "B.Fab")
		)
		(pad "1" smd rect
			(at 0.2667 0 90)
			(size 0.3048 0.381)
			(layers "B.Cu" "B.Mask" "B.Paste")
			(net "P1V25_PEX3")
		)
		(pad "2" smd rect
			(at -0.2667 0 90)
			(size 0.3048 0.381)
			(layers "B.Cu" "B.Mask" "B.Paste")
			(net "GND")
		)
	)
)
